# TIMECARD (Time Appliance Project (Time Card)) — schematic netlist excerpt (pin names and nets, part order shuffled) for the footprints in the layout excerpt that follows; sources: Cadence DE-HDL packaged netlist, KiCad conversion of R4006-B0001-02_R01.brd

U9  CL1001485A  pkg SOT23_6  page 21
  \1\  = NC
  \2\  = SG
  \3\  = NC
  \4\  = CONN_MICRO_USB_DM
  \5\  = XP5R0V_USB_CONN
  \6\  = CONN_MICRO_USB_DP

(kicad_pcb
	(version 20260206)
	(generator "pcbnew")
	(generator_version "10.0")
	(general
		(thickness 1.6)
		(legacy_teardrops no)
	)
	(paper "A4")
	(title_block
		(title "timecard-production-celestica-r4006 — R4006-B0001-02_R01.brd")
		(comment 1 "Time Appliance Project (Time Card) / footprint 325 of 1113 (U9), pads 1-6 of 6")
	)
	(layers
		(0 "F.Cu" signal "TOP")
		(4 "In1.Cu" signal "L02_GND1")
		(6 "In2.Cu" signal "L03_SIG1")
		(8 "In3.Cu" signal "L04_GND2")
		(10 "In4.Cu" signal "L05_VCC1")
		(12 "In5.Cu" signal "L06_VCC2")
		(14 "In6.Cu" signal "L07_GND3")
		(16 "In7.Cu" signal "L08_SIG2")
		(18 "In8.Cu" signal "L09_GND4")
		(2 "B.Cu" signal "BOTTOM")
		(9 "F.Adhes" user "F.Adhesive")
		(11 "B.Adhes" user "B.Adhesive")
		(13 "F.Paste" user "Package Geometry/Pastemask Top")
		(15 "B.Paste" user "Package Geometry/Pastemask Bottom")
		(5 "F.SilkS" user "Ref Des/Silkscreen Top")
		(7 "B.SilkS" user "Ref Des/Silkscreen Bottom")
		(1 "F.Mask" user "Board Geometry/Soldermask Top")
		(3 "B.Mask" user "Board Geometry/Soldermask Bottom")
		(17 "Dwgs.User" user "User.Drawings")
		(19 "Cmts.User" user "User.Comments")
		(21 "Eco1.User" user "User.Eco1")
		(23 "Eco2.User" user "User.Eco2")
		(25 "Edge.Cuts" user "Board Geometry/Outline")
		(27 "Margin" user)
		(31 "F.CrtYd" user "Package Geometry/Place Bound Top")
		(29 "B.CrtYd" user "Package Geometry/Place Bound Bottom")
		(35 "F.Fab" user "Ref Des/Assembly Top")
		(33 "B.Fab" user "Ref Des/Assembly Bottom")
	)
	(footprint ""
		(layer "F.Cu")
		(at 159.255206 -57.361836 -90)
		(property "Reference" "U9"
			(at -3.812794 -0.129794 0)
			(unlocked yes)
			(layer "F.SilkS")
			(effects
				(font
					(size 0.7874 0.5842)
					(thickness 0.1524)
				)
			)
		)
		(property "Value" ""
			(at 0 0 270)
			(layer "F.Fab")
			(effects
				(font
					(size 1.27 1.27)
				)
			)
		)
		(property "User Part Number" "PARTNUM*"
			(at 0.1016 3.45567 270)
			(unlocked yes)
			(layer "Cmts.User")
			(hide yes)
			(effects
				(font
					(size 0.7874 0.5842)
					(thickness 0.1524)
				)
			)
		)
		(property "Device Type" "CL1001485A-G122-00019-01"
			(at 0.1016 2.54127 270)
			(unlocked yes)
			(layer "F.Fab")
			(hide yes)
			(effects
				(font
					(size 0.7874 0.5842)
					(thickness 0.1524)
				)
			)
		)
		(duplicate_pad_numbers_are_jumpers no)
		(pad "1" smd rect
			(at -1.4351 -0.94996)
			(size 0.508 1.1938)
			(layers "F.Cu" "F.Mask" "F.Paste")
			(net "Net_758")
		)
		(pad "2" smd rect
			(at -1.4351 0)
			(size 0.508 1.1938)
			(layers "F.Cu" "F.Mask" "F.Paste")
			(net "SG")
		)
		(pad "3" smd rect
			(at -1.4351 0.94996)
			(size 0.508 1.1938)
			(layers "F.Cu" "F.Mask" "F.Paste")
			(net "Net_757")
		)
		(pad "4" smd rect
			(at 1.4351 0.94996)
			(size 0.508 1.1938)
			(layers "F.Cu" "F.Mask" "F.Paste")
			(net "CONN_MICRO_USB_DM")
		)
		(pad "5" smd rect
			(at 1.4351 0)
			(size 0.508 1.1938)
			(layers "F.Cu" "F.Mask" "F.Paste")
			(net "XP5R0V_USB_CONN")
		)
		(pad "6" smd rect
			(at 1.4351 -0.94996)
			(size 0.508 1.1938)
			(layers "F.Cu" "F.Mask" "F.Paste")
			(net "CONN_MICRO_USB_DP")
		)
	)
)
